(kicad_pcb
	(version 20221018)
	(generator pcbnew)
	(general
    (thickness 1.518)
  )
	(paper "A4")
	(title_block
    (title "Kria K26 Devboard")
    (date "2024-03-26")
    (rev "1.2.5")
    (comment 1 "www.antmicro.com")
    (comment 2 "Antmicro Ltd.")
		(comment 9 "footprints 647-656 of 660")
	)
	(layers
    (0 "F.Cu" mixed)
    (1 "In1.Cu" power)
    (2 "In2.Cu" mixed)
    (3 "In3.Cu" power)
    (4 "In4.Cu" mixed)
    (5 "In5.Cu" power)
    (6 "In6.Cu" mixed)
    (31 "B.Cu" power)
    (32 "B.Adhes" user "B.Adhesive")
    (33 "F.Adhes" user "F.Adhesive")
    (34 "B.Paste" user)
    (35 "F.Paste" user)
    (36 "B.SilkS" user "B.Silkscreen")
    (37 "F.SilkS" user "F.Silkscreen")
    (38 "B.Mask" user)
    (39 "F.Mask" user)
    (40 "Dwgs.User" user "User.Drawings")
    (41 "Cmts.User" user "User.Comments")
    (42 "Eco1.User" user "User.Eco1")
    (43 "Eco2.User" user "User.Eco2")
    (44 "Edge.Cuts" user)
    (45 "Margin" user)
    (46 "B.CrtYd" user "B.Courtyard")
    (47 "F.CrtYd" user "F.Courtyard")
    (48 "B.Fab" user)
    (49 "F.Fab" user)
  )
	(footprint "kria-k26-devboard-footprints:C_0402_1005Metric" (layer "B.Cu")
    (at 145.95 121.65 90)
    (descr "Capacitor SMD 0402")
    (tags "capacitor SMD 0402")
    (property "Author" "Antmicro")
    (property "Dielectric" "")
    (property "License" "Apache-2.0")
    (property "MPN" "GRM155R61A475MEAAD")
    (property "Manufacturer" "Murata")
    (property "Sheetfile" "debug.kicad_sch")
    (property "Sheetname" "Debug and JTAG")
    (property "Val" "4u7")
    (property "Voltage" "")
    (property "ki_description" " ")
    (attr smd)
    (fp_text reference "C242" (at -1.31 -0.61 90) (layer "B.SilkS")
        (effects (font (size 0.7 0.7) (thickness 0.15)) (justify right bottom mirror))
    )
    (fp_text value "C_4u7_0402" (at 0 -1.4 90) (layer "B.Fab") hide
        (effects (font (size 0.7 0.7) (thickness 0.15)) (justify right bottom mirror))
    )
    (fp_text user "Author: Antmicro" (at -0.932 -4.17 90) (layer "B.Fab") hide
        (effects (font (size 0.7 0.7) (thickness 0.15)) (justify right bottom mirror))
    )
    (fp_text user "License: Apache-2.0" (at -0.932 -5.17 90) (layer "B.Fab") hide
        (effects (font (size 0.7 0.7) (thickness 0.15)) (justify right bottom mirror))
    )
    (fp_text user "${REFERENCE}" (at -0.932 -3.168 90) (layer "B.Fab") hide
        (effects (font (size 0.7 0.7) (thickness 0.15)) (justify right bottom mirror))
    )
    (fp_rect (start -0.94 0.47) (end 0.94 -0.47)
      (stroke (width 0.05) (type solid)) (fill none) (layer "B.CrtYd"))
    (fp_rect (start -0.499 0.249) (end 0.499 -0.249)
      (stroke (width 0.15) (type solid)) (fill none) (layer "B.Fab"))
    (pad "1" smd roundrect (at -0.484 0 90) (size 0.59 0.64) (layers "B.Cu" "B.Paste" "B.Mask") (roundrect_rratio 0.25)
      (net 132 "/Debug and JTAG/USB_1V2") (pintype "passive"))
    (pad "2" smd roundrect (at 0.484 0 90) (size 0.59 0.64) (layers "B.Cu" "B.Paste" "B.Mask") (roundrect_rratio 0.25)
      (net 1 "GND") (pintype "passive"))
  )
	(footprint "kria-k26-devboard-footprints:Fiducial_1mm_Mask2mm" (layer "B.Cu")
    (at 182.9 149.2 90)
    (descr "Circular Fiducial, 1mm bare copper, 3mm soldermask opening")
    (tags "fiducial")
    (attr smd board_only exclude_from_bom)
    (fp_text reference "FID5" (at -0.07 -3.21) (layer "B.SilkS")
        (effects (font (size 1 1) (thickness 0.15)) (justify mirror))
    )
    (fp_text value "Fiducial_1mm_Mask2mm" (at 0 -2.6035 90) (layer "B.Fab") hide
        (effects (font (size 1 1) (thickness 0.15)) (justify mirror))
    )
    (fp_text user "Author: Antmicro" (at -1.25 -5.803 270) (layer "B.Fab") hide
        (effects (font (size 0.7 0.7) (thickness 0.15)) (justify left bottom mirror))
    )
    (fp_text user "License: Apache-2.0" (at -1.25 -7.003 270) (layer "B.Fab") hide
        (effects (font (size 0.7 0.7) (thickness 0.15)) (justify left bottom mirror))
    )
    (fp_text user "${REFERENCE}" (at 0 0 90) (layer "B.Fab")
        (effects (font (size 0.4 0.4) (thickness 0.06)) (justify mirror))
    )
    (fp_circle (center 0 0) (end 1.24 0)
      (stroke (width 0.05) (type solid)) (fill none) (layer "B.CrtYd"))
    (fp_circle (center 0 0) (end 0.999 0)
      (stroke (width 0.15) (type solid)) (fill none) (layer "B.Fab"))
    (pad "" smd circle (at 0 0 90) (size 1 1) (layers "B.Cu" "B.Mask")
      (solder_mask_margin 0.5) (clearance 0.5))
  )
	(footprint "kria-k26-devboard-footprints:R_0805_2012Metric" (layer "B.Cu")
    (at 187.2 75.5 90)
    (property "Author" "Antmicro")
    (property "License" "Apache-2.0")
    (property "MPN" "CR0805-FX-3242ELF")
    (property "Manufacturer" "Bourns")
    (property "Sheetfile" "PoE.kicad_sch")
    (property "Sheetname" "PoE")
    (property "Tolerance" "1%")
    (property "Val" "32k4")
    (property "ki_description" "32k4 resistor in 0805 package with 1% tolerance")
    (attr smd)
    (fp_text reference "R117" (at 1.5 1.89 270) (layer "B.SilkS")
        (effects (font (size 0.7 0.7) (thickness 0.15)) (justify left bottom mirror))
    )
    (fp_text value "R_32k4_0805" (at 0 -1.8 270) (layer "B.Fab") hide
        (effects (font (size 0.7 0.7) (thickness 0.15)) (justify left bottom mirror))
    )
    (fp_text user "License: Apache-2.0" (at -1.9 -5.75 270) (layer "B.Fab") hide
        (effects (font (size 0.7 0.7) (thickness 0.15)) (justify left bottom mirror))
    )
    (fp_text user "${REFERENCE}" (at -1.9 -3.1 270) (layer "B.Fab") hide
        (effects (font (size 0.7 0.7) (thickness 0.15)) (justify left bottom mirror))
    )
    (fp_text user "Author: Antmicro" (at -1.9 -4.4 270) (layer "B.Fab") hide
        (effects (font (size 0.7 0.7) (thickness 0.15)) (justify left bottom mirror))
    )
    (fp_line (start -0.32 -0.699) (end 0.28 -0.699)
      (stroke (width 0.15) (type solid)) (layer "B.SilkS"))
    (fp_line (start -0.3 0.701) (end 0.298 0.701)
      (stroke (width 0.15) (type solid)) (layer "B.SilkS"))
    (fp_rect (start -1.75 0.85) (end 1.75 -0.85)
      (stroke (width 0.05) (type solid)) (fill none) (layer "B.CrtYd"))
    (fp_line (start -0.951 -0.68) (end 0.949 -0.68)
      (stroke (width 0.15) (type solid)) (layer "B.Fab"))
    (fp_line (start -0.951 0.677) (end -0.951 -0.675)
      (stroke (width 0.15) (type solid)) (layer "B.Fab"))
    (fp_line (start -0.951 0.682) (end 0.949 0.682)
      (stroke (width 0.15) (type solid)) (layer "B.Fab"))
    (fp_line (start 0.949 0.677) (end 0.949 -0.675)
      (stroke (width 0.15) (type solid)) (layer "B.Fab"))
    (pad "1" smd roundrect (at -1.1 0.001 90) (size 1 1.4) (layers "B.Cu" "B.Paste" "B.Mask") (roundrect_rratio 0.15)
      (net 7 "Net-(D11-Pad1)") (pintype "passive"))
    (pad "2" smd roundrect (at 1.1 0.001 90) (size 1 1.4) (layers "B.Cu" "B.Paste" "B.Mask") (roundrect_rratio 0.15)
      (net 9 "/Power Supply/PoE/VDD_POE_IN") (pintype "passive"))
  )
	(footprint "kria-k26-devboard-footprints:R_0402_1005Metric" (layer "B.Cu")
    (at 173.925 129.025 90)
    (descr "Resistor SMD 0402")
    (tags "resistor SMD 0402")
    (property "Author" "Antmicro")
    (property "Current" "1A")
    (property "DNP" "DNP")
    (property "License" "Apache-2.0")
    (property "MPN" "ERJ2GE0R00X")
    (property "Manufacturer" "Panasonic")
    (property "Sheetfile" "dc-dc-conventers.kicad_sch")
    (property "Sheetname" "DC/DC conventers")
    (property "Tolerance" "")
    (property "Val" "0R")
    (property "dnp" "")
    (property "exclude_from_bom" "")
    (property "ki_description" "0R resistor in 0402 package with unspecified tolerance")
    (attr exclude_from_pos_files exclude_from_bom)
    (fp_text reference "R166" (at -0.805 0.385 270) (layer "B.SilkS")
        (effects (font (size 0.7 0.7) (thickness 0.15)) (justify left bottom mirror))
    )
    (fp_text value "R_0R_0402" (at 0 -1.4 270) (layer "B.Fab") hide
        (effects (font (size 0.7 0.7) (thickness 0.15)) (justify left bottom mirror))
    )
    (fp_text user "${REFERENCE}" (at -0.95 -3.168 270) (layer "B.Fab") hide
        (effects (font (size 0.7 0.7) (thickness 0.15)) (justify left bottom mirror))
    )
    (fp_text user "License: Apache-2.0" (at -0.95 -5.169 270) (layer "B.Fab") hide
        (effects (font (size 0.7 0.7) (thickness 0.15)) (justify left bottom mirror))
    )
    (fp_text user "Author: Antmicro" (at -0.95 -4.169 270) (layer "B.Fab") hide
        (effects (font (size 0.7 0.7) (thickness 0.15)) (justify left bottom mirror))
    )
    (fp_rect (start -0.93 0.47) (end 0.93 -0.47)
      (stroke (width 0.05) (type solid)) (fill none) (layer "B.CrtYd"))
    (fp_rect (start -0.5 0.25) (end 0.5 -0.25)
      (stroke (width 0.15) (type solid)) (fill none) (layer "B.Fab"))
    (pad "1" smd roundrect (at -0.485 0 90) (size 0.59 0.64) (layers "B.Cu" "B.Paste" "B.Mask") (roundrect_rratio 0.25)
      (net 8 "SOM_5V0") (pintype "passive"))
    (pad "2" smd roundrect (at 0.485 0 90) (size 0.59 0.64) (layers "B.Cu" "B.Paste" "B.Mask") (roundrect_rratio 0.25)
      (net 774 "/Power Supply/DC/DC conventers/SOM_5V_FB") (pintype "passive"))
  )
	(footprint "kria-k26-devboard-footprints:C_0402_1005Metric" (layer "B.Cu")
    (at 95.75 66.525)
    (descr "Capacitor SMD 0402")
    (tags "capacitor SMD 0402")
    (property "Author" "Antmicro")
    (property "Dielectric" "X5R")
    (property "License" "Apache-2.0")
    (property "MPN" "GRM155R61H104KE14D")
    (property "Manufacturer" "Murata")
    (property "Sheetfile" "dp.kicad_sch")
    (property "Sheetname" "Display Port")
    (property "Val" "100n")
    (property "Voltage" "50V")
    (property "ki_description" " ")
    (attr smd)
    (fp_text reference "C248" (at 3.705001 0.355 180) (layer "B.SilkS")
        (effects (font (size 0.7 0.7) (thickness 0.15)) (justify left bottom mirror))
    )
    (fp_text value "C_100n_0402" (at 0 -1.4 180) (layer "B.Fab") hide
        (effects (font (size 0.7 0.7) (thickness 0.15)) (justify left bottom mirror))
    )
    (fp_text user "License: Apache-2.0" (at -0.932 -5.17 180) (layer "B.Fab") hide
        (effects (font (size 0.7 0.7) (thickness 0.15)) (justify left bottom mirror))
    )
    (fp_text user "Author: Antmicro" (at -0.932 -4.17 180) (layer "B.Fab") hide
        (effects (font (size 0.7 0.7) (thickness 0.15)) (justify left bottom mirror))
    )
    (fp_text user "${REFERENCE}" (at -0.932 -3.168 180) (layer "B.Fab") hide
        (effects (font (size 0.7 0.7) (thickness 0.15)) (justify left bottom mirror))
    )
    (fp_rect (start -0.94 0.47) (end 0.94 -0.47)
      (stroke (width 0.05) (type solid)) (fill none) (layer "B.CrtYd"))
    (fp_rect (start -0.499 0.249) (end 0.499 -0.249)
      (stroke (width 0.15) (type solid)) (fill none) (layer "B.Fab"))
    (pad "1" smd roundrect (at -0.484 0) (size 0.59 0.64) (layers "B.Cu" "B.Paste" "B.Mask") (roundrect_rratio 0.25)
      (net 334 "Net-(J1-DP_PWR)") (pintype "passive"))
    (pad "2" smd roundrect (at 0.484 0) (size 0.59 0.64) (layers "B.Cu" "B.Paste" "B.Mask") (roundrect_rratio 0.25)
      (net 1 "GND") (pintype "passive"))
  )
	(footprint "kria-k26-devboard-footprints:C_0402_1005Metric" (layer "B.Cu")
    (at 107 87.6 180)
    (descr "Capacitor SMD 0402")
    (tags "capacitor SMD 0402")
    (property "Author" "Antmicro")
    (property "Dielectric" "X5R")
    (property "License" "Apache-2.0")
    (property "MPN" "GRM155R61H104KE14D")
    (property "Manufacturer" "Murata")
    (property "Sheetfile" "k26_som.kicad_sch")
    (property "Sheetname" "Xilinx K26 SOM")
    (property "Val" "100n")
    (property "Voltage" "50V")
    (property "ki_description" " ")
    (attr smd)
    (fp_text reference "C252" (at 0.13 -3.55) (layer "B.SilkS")
        (effects (font (size 0.7 0.7) (thickness 0.15)) (justify left bottom mirror))
    )
    (fp_text value "C_100n_0402" (at 0 -1.4) (layer "B.Fab") hide
        (effects (font (size 0.7 0.7) (thickness 0.15)) (justify left bottom mirror))
    )
    (fp_text user "Author: Antmicro" (at -0.932 -4.17) (layer "B.Fab") hide
        (effects (font (size 0.7 0.7) (thickness 0.15)) (justify left bottom mirror))
    )
    (fp_text user "License: Apache-2.0" (at -0.932 -5.17) (layer "B.Fab") hide
        (effects (font (size 0.7 0.7) (thickness 0.15)) (justify left bottom mirror))
    )
    (fp_text user "${REFERENCE}" (at -0.932 -3.168) (layer "B.Fab") hide
        (effects (font (size 0.7 0.7) (thickness 0.15)) (justify left bottom mirror))
    )
    (fp_rect (start -0.94 0.47) (end 0.94 -0.47)
      (stroke (width 0.05) (type solid)) (fill none) (layer "B.CrtYd"))
    (fp_rect (start -0.499 0.249) (end 0.499 -0.249)
      (stroke (width 0.15) (type solid)) (fill none) (layer "B.Fab"))
    (pad "1" smd roundrect (at -0.484 0 180) (size 0.59 0.64) (layers "B.Cu" "B.Paste" "B.Mask") (roundrect_rratio 0.25)
      (net 243 "Net-(Q6-D)") (pintype "passive"))
    (pad "2" smd roundrect (at 0.484 0 180) (size 0.59 0.64) (layers "B.Cu" "B.Paste" "B.Mask") (roundrect_rratio 0.25)
      (net 1 "GND") (pintype "passive"))
  )
	(footprint "kria-k26-devboard-footprints:C_0402_1005Metric" (layer "B.Cu")
    (at 107 88.6 180)
    (descr "Capacitor SMD 0402")
    (tags "capacitor SMD 0402")
    (property "Author" "Antmicro")
    (property "Dielectric" "X5R")
    (property "License" "Apache-2.0")
    (property "MPN" "GRM155R61H104KE14D")
    (property "Manufacturer" "Murata")
    (property "Sheetfile" "k26_som.kicad_sch")
    (property "Sheetname" "Xilinx K26 SOM")
    (property "Val" "100n")
    (property "Voltage" "50V")
    (property "ki_description" " ")
    (attr smd)
    (fp_text reference "C253" (at 0.13 -3.55) (layer "B.SilkS")
        (effects (font (size 0.7 0.7) (thickness 0.15)) (justify left bottom mirror))
    )
    (fp_text value "C_100n_0402" (at 0 -1.4) (layer "B.Fab") hide
        (effects (font (size 0.7 0.7) (thickness 0.15)) (justify left bottom mirror))
    )
    (fp_text user "License: Apache-2.0" (at -0.932 -5.17) (layer "B.Fab") hide
        (effects (font (size 0.7 0.7) (thickness 0.15)) (justify left bottom mirror))
    )
    (fp_text user "Author: Antmicro" (at -0.932 -4.17) (layer "B.Fab") hide
        (effects (font (size 0.7 0.7) (thickness 0.15)) (justify left bottom mirror))
    )
    (fp_text user "${REFERENCE}" (at -0.932 -3.168) (layer "B.Fab") hide
        (effects (font (size 0.7 0.7) (thickness 0.15)) (justify left bottom mirror))
    )
    (fp_rect (start -0.94 0.47) (end 0.94 -0.47)
      (stroke (width 0.05) (type solid)) (fill none) (layer "B.CrtYd"))
    (fp_rect (start -0.499 0.249) (end 0.499 -0.249)
      (stroke (width 0.15) (type solid)) (fill none) (layer "B.Fab"))
    (pad "1" smd roundrect (at -0.484 0 180) (size 0.59 0.64) (layers "B.Cu" "B.Paste" "B.Mask") (roundrect_rratio 0.25)
      (net 243 "Net-(Q6-D)") (pintype "passive"))
    (pad "2" smd roundrect (at 0.484 0 180) (size 0.59 0.64) (layers "B.Cu" "B.Paste" "B.Mask") (roundrect_rratio 0.25)
      (net 1 "GND") (pintype "passive"))
  )
	(footprint "kria-k26-devboard-footprints:R_0603_1608Metric" (layer "B.Cu")
    (at 134.85 96.95 -90)
    (descr "Resistor SMD 0603")
    (tags "resistor SMD 0603")
    (property "Author" "Antmicro")
    (property "License" "Apache-2.0")
    (property "MPN" "PMR03EZPJ000")
    (property "Manufacturer" "ROHM Semiconductor")
    (property "Max. Curr." "22.4A")
    (property "Sheetfile" "dc-dc-conventers.kicad_sch")
    (property "Sheetname" "DC/DC conventers")
    (property "Val" "0R")
    (property "ki_description" "Metal strip 0Ohm jumper 22.4A")
    (property "ki_keywords" "Metal strip 0Ohm jumper 22.4A high power hpwr current")
    (attr smd)
    (fp_text reference "R157" (at -1.33 0.84 90) (layer "B.SilkS")
        (effects (font (size 0.7 0.7) (thickness 0.15)) (justify left bottom mirror))
    )
    (fp_text value "R_0R_22.4A_0603" (at 0 -1.6 90) (layer "B.Fab") hide
        (effects (font (size 0.7 0.7) (thickness 0.15)) (justify left bottom mirror))
    )
    (fp_text user "License: Apache-2.0" (at -1.25 -5.9 90) (layer "B.Fab") hide
        (effects (font (size 0.7 0.7) (thickness 0.15)) (justify left bottom mirror))
    )
    (fp_text user "${REFERENCE}" (at -1.25 -3.898 90) (layer "B.Fab") hide
        (effects (font (size 0.7 0.7) (thickness 0.15)) (justify left bottom mirror))
    )
    (fp_text user "Author: Antmicro" (at -1.25 -4.9 90) (layer "B.Fab") hide
        (effects (font (size 0.7 0.7) (thickness 0.15)) (justify left bottom mirror))
    )
    (fp_line (start -0.3 -0.3) (end 0.3 -0.3)
      (stroke (width 0.15) (type solid)) (layer "B.SilkS"))
    (fp_line (start -0.3 0.3) (end 0.3 0.3)
      (stroke (width 0.15) (type solid)) (layer "B.SilkS"))
    (fp_rect (start -1.25 0.7) (end 1.25 -0.7)
      (stroke (width 0.05) (type solid)) (fill none) (layer "B.CrtYd"))
    (fp_rect (start -0.8 0.4) (end 0.8 -0.4)
      (stroke (width 0.15) (type solid)) (fill none) (layer "B.Fab"))
    (pad "1" smd roundrect (at -0.7 0 270) (size 0.6 0.8) (layers "B.Cu" "B.Paste" "B.Mask") (roundrect_rratio 0.2)
      (net 769 "/Power Supply/DC/DC conventers/PS_1V0_OUT") (pintype "passive"))
    (pad "2" smd roundrect (at 0.7 0 270) (size 0.6 0.8) (layers "B.Cu" "B.Paste" "B.Mask") (roundrect_rratio 0.2)
      (net 19 "PS_1V0") (pintype "passive"))
  )
	(footprint "kria-k26-devboard-footprints:R_0402_1005Metric" (layer "B.Cu")
    (at 110.425 96.45 -90)
    (descr "Resistor SMD 0402")
    (tags "resistor SMD 0402")
    (property "Author" "Antmicro")
    (property "DNP" "DNP")
    (property "License" "Apache-2.0")
    (property "MPN" "CR0402-FX-1003GLF")
    (property "Manufacturer" "Bourns")
    (property "Sheetfile" "clock.kicad_sch")
    (property "Sheetname" "Clock distribution")
    (property "Tolerance" "1%")
    (property "Val" "100k")
    (property "dnp" "")
    (property "exclude_from_bom" "")
    (property "ki_description" "100k resistor in 0402 package with 1% tolerance")
    (attr exclude_from_pos_files exclude_from_bom)
    (fp_text reference "R176" (at -1.32 0.625 90) (layer "B.SilkS")
        (effects (font (size 0.7 0.7) (thickness 0.15)) (justify left bottom mirror))
    )
    (fp_text value "R_100k_0402" (at 0 -1.4 90) (layer "B.Fab") hide
        (effects (font (size 0.7 0.7) (thickness 0.15)) (justify left bottom mirror))
    )
    (fp_text user "License: Apache-2.0" (at -0.95 -5.169 90) (layer "B.Fab") hide
        (effects (font (size 0.7 0.7) (thickness 0.15)) (justify left bottom mirror))
    )
    (fp_text user "Author: Antmicro" (at -0.95 -4.169 90) (layer "B.Fab") hide
        (effects (font (size 0.7 0.7) (thickness 0.15)) (justify left bottom mirror))
    )
    (fp_text user "${REFERENCE}" (at -0.95 -3.168 90) (layer "B.Fab") hide
        (effects (font (size 0.7 0.7) (thickness 0.15)) (justify left bottom mirror))
    )
    (fp_rect (start -0.93 0.47) (end 0.93 -0.47)
      (stroke (width 0.05) (type solid)) (fill none) (layer "B.CrtYd"))
    (fp_rect (start -0.5 0.25) (end 0.5 -0.25)
      (stroke (width 0.15) (type solid)) (fill none) (layer "B.Fab"))
    (pad "1" smd roundrect (at -0.485 0 270) (size 0.59 0.64) (layers "B.Cu" "B.Paste" "B.Mask") (roundrect_rratio 0.25)
      (net 1 "GND") (pintype "passive"))
    (pad "2" smd roundrect (at 0.485 0 270) (size 0.59 0.64) (layers "B.Cu" "B.Paste" "B.Mask") (roundrect_rratio 0.25)
      (net 698 "Net-(U8-IN)") (pintype "passive"))
  )
	(footprint "kria-k26-devboard-footprints:R_0402_1005Metric" (layer "B.Cu")
    (at 129.97 81.91 90)
    (descr "Resistor SMD 0402")
    (tags "resistor SMD 0402")
    (property "Author" "Antmicro")
    (property "DNP" "DNP")
    (property "License" "Apache-2.0")
    (property "MPN" "CR0402-FX-5111GLF")
    (property "Manufacturer" "Bourns")
    (property "Sheetfile" "usb.kicad_sch")
    (property "Sheetname" "USB")
    (property "Tolerance" "1%")
    (property "Val" "5k11")
    (property "dnp" "")
    (property "exclude_from_bom" "")
    (property "ki_description" "5k11 resistor in 0402 package with 1% tolerance")
    (attr exclude_from_pos_files exclude_from_bom)
    (fp_text reference "R171" (at 1.29 1.37 270) (layer "B.SilkS")
        (effects (font (size 0.7 0.7) (thickness 0.15)) (justify left bottom mirror))
    )
    (fp_text value "R_5k11_0402" (at 0 -1.4 270) (layer "B.Fab") hide
        (effects (font (size 0.7 0.7) (thickness 0.15)) (justify left bottom mirror))
    )
    (fp_text user "Author: Antmicro" (at -0.95 -4.169 270) (layer "B.Fab") hide
        (effects (font (size 0.7 0.7) (thickness 0.15)) (justify left bottom mirror))
    )
    (fp_text user "${REFERENCE}" (at -0.95 -3.168 270) (layer "B.Fab") hide
        (effects (font (size 0.7 0.7) (thickness 0.15)) (justify left bottom mirror))
    )
    (fp_text user "License: Apache-2.0" (at -0.95 -5.169 270) (layer "B.Fab") hide
        (effects (font (size 0.7 0.7) (thickness 0.15)) (justify left bottom mirror))
    )
    (fp_rect (start -0.93 0.47) (end 0.93 -0.47)
      (stroke (width 0.05) (type solid)) (fill none) (layer "B.CrtYd"))
    (fp_rect (start -0.5 0.25) (end 0.5 -0.25)
      (stroke (width 0.15) (type solid)) (fill none) (layer "B.Fab"))
    (pad "1" smd roundrect (at -0.485 0 90) (size 0.59 0.64) (layers "B.Cu" "B.Paste" "B.Mask") (roundrect_rratio 0.25)
      (net 696 "Net-(U17-DP1_CC2)") (pintype "passive"))
    (pad "2" smd roundrect (at 0.485 0 90) (size 0.59 0.64) (layers "B.Cu" "B.Paste" "B.Mask") (roundrect_rratio 0.25)
      (net 1 "GND") (pintype "passive"))
  )
)
